# S9S_MB_2U (Grand Teton) — schematic netlist excerpt (pin names and nets, part order shuffled) for the footprints in the layout excerpt that follows; sources: Cadence DE-HDL packaged netlist, KiCad conversion of 03242023_DA0F0TMBIJ0_F0T_Motherboard_J_brd_V01_OCP.brd

R1800  Q_RES  1.21K 1% CHIP  pkg 0402LF  page 250 : A = P12V_AUX_ADC ; B = GND
PC2948  Q_CAP  2.2UF 10V 10% X6S  pkg C0402  page 279 : A = PVCCFA_EHV_CPU0_PVCC ; B = GND

(kicad_pcb
	(version 20260206)
	(generator "pcbnew")
	(generator_version "10.0")
	(general
		(thickness 1.6)
		(legacy_teardrops no)
	)
	(paper "A4")
	(title_block
		(title "03242023_DA0F0TMBIJ0_F0T_Motherboard_J_brd_V01_OCP.brd")
		(comment 1 "Grand Teton / footprints 1069-1070 of 6105")
	)
	(layers
		(0 "F.Cu" signal "TOP")
		(4 "In1.Cu" signal "GND")
		(6 "In2.Cu" signal "IN1")
		(8 "In3.Cu" signal "GND1")
		(10 "In4.Cu" signal "IN2")
		(12 "In5.Cu" signal "GND2")
		(14 "In6.Cu" signal "IN3")
		(16 "In7.Cu" signal "GND3")
		(18 "In8.Cu" signal "VCC")
		(20 "In9.Cu" signal "VCC1")
		(22 "In10.Cu" signal "GND4")
		(24 "In11.Cu" signal "IN4")
		(26 "In12.Cu" signal "GND5")
		(28 "In13.Cu" signal "IN5")
		(30 "In14.Cu" signal "GND6")
		(32 "In15.Cu" signal "IN6")
		(34 "In16.Cu" signal "GND7")
		(2 "B.Cu" signal "BOTTOM")
		(9 "F.Adhes" user "F.Adhesive")
		(11 "B.Adhes" user "B.Adhesive")
		(13 "F.Paste" user "Package Geometry/Pastemask Top")
		(15 "B.Paste" user "Package Geometry/Pastemask Bottom")
		(5 "F.SilkS" user "Ref Des/Silkscreen Top")
		(7 "B.SilkS" user "Ref Des/Silkscreen Bottom")
		(1 "F.Mask" user "Board Geometry/Soldermask Top")
		(3 "B.Mask" user "Board Geometry/Soldermask Bottom")
		(17 "Dwgs.User" user "User.Drawings")
		(19 "Cmts.User" user "User.Comments")
		(21 "Eco1.User" user "User.Eco1")
		(23 "Eco2.User" user "User.Eco2")
		(25 "Edge.Cuts" user "Board Geometry/Outline")
		(27 "Margin" user)
		(31 "F.CrtYd" user "Package Geometry/Place Bound Top")
		(29 "B.CrtYd" user "Package Geometry/Place Bound Bottom")
		(35 "F.Fab" user "Ref Des/Assembly Top")
		(33 "B.Fab" user "Ref Des/Assembly Bottom")
	)
	(footprint ""
		(layer "F.Cu")
		(at 44.169584 -112.619282)
		(property "Reference" "R1800"
			(at 0 0 0)
			(layer "F.SilkS")
			(hide yes)
			(effects
				(font
					(size 1.27 1.27)
				)
			)
		)
		(property "Value" ""
			(at 0 0 0)
			(layer "F.Fab")
			(effects
				(font
					(size 1.27 1.27)
				)
			)
		)
		(duplicate_pad_numbers_are_jumpers no)
		(fp_line
			(start -0.7874 -0.4064)
			(end 0.7874 -0.4064)
			(stroke
				(width 0.1524)
				(type default)
			)
			(layer "F.SilkS")
		)
		(fp_line
			(start -0.7874 0.4064)
			(end -0.7874 -0.4064)
			(stroke
				(width 0.1524)
				(type default)
			)
			(layer "F.SilkS")
		)
		(fp_line
			(start 0.7874 -0.4064)
			(end 0.7874 0.4064)
			(stroke
				(width 0.1524)
				(type default)
			)
			(layer "F.SilkS")
		)
		(fp_line
			(start 0.7874 0.4064)
			(end -0.7874 0.4064)
			(stroke
				(width 0.1524)
				(type default)
			)
			(layer "F.SilkS")
		)
		(fp_line
			(start -0.67945 -0.305054)
			(end -0.12065 -0.305054)
			(stroke
				(width 0.1)
				(type default)
			)
			(layer "F.Fab")
		)
		(fp_line
			(start -0.67945 0.3048)
			(end -0.67945 -0.305054)
			(stroke
				(width 0.1)
				(type default)
			)
			(layer "F.Fab")
		)
		(fp_line
			(start -0.12065 -0.305054)
			(end -0.12065 -0.2794)
			(stroke
				(width 0.1)
				(type default)
			)
			(layer "F.Fab")
		)
		(fp_line
			(start -0.12065 -0.2794)
			(end 0.12065 -0.2794)
			(stroke
				(width 0.1)
				(type default)
			)
			(layer "F.Fab")
		)
		(fp_line
			(start -0.12065 0.2794)
			(end -0.12065 0.3048)
			(stroke
				(width 0.1)
				(type default)
			)
			(layer "F.Fab")
		)
		(fp_line
			(start -0.12065 0.3048)
			(end -0.67945 0.3048)
			(stroke
				(width 0.1)
				(type default)
			)
			(layer "F.Fab")
		)
		(fp_line
			(start 0.120396 0.2794)
			(end -0.12065 0.2794)
			(stroke
				(width 0.1)
				(type default)
			)
			(layer "F.Fab")
		)
		(fp_line
			(start 0.120396 0.3048)
			(end 0.120396 0.2794)
			(stroke
				(width 0.1)
				(type default)
			)
			(layer "F.Fab")
		)
		(fp_line
			(start 0.12065 -0.3048)
			(end 0.67945 -0.3048)
			(stroke
				(width 0.1)
				(type default)
			)
			(layer "F.Fab")
		)
		(fp_line
			(start 0.12065 -0.2794)
			(end 0.12065 -0.3048)
			(stroke
				(width 0.1)
				(type default)
			)
			(layer "F.Fab")
		)
		(fp_line
			(start 0.67945 -0.3048)
			(end 0.67945 0.3048)
			(stroke
				(width 0.1)
				(type default)
			)
			(layer "F.Fab")
		)
		(fp_line
			(start 0.67945 0.3048)
			(end 0.120396 0.3048)
			(stroke
				(width 0.1)
				(type default)
			)
			(layer "F.Fab")
		)
		(pad "1" smd circle
			(at -0.40005 0)
			(size 0 0)
			(layers "F.Cu" "F.Mask" "F.Paste")
			(net "P12V_AUX_ADC")
		)
		(pad "2" smd circle
			(at 0.40005 0)
			(size 0 0)
			(layers "F.Cu" "F.Mask" "F.Paste")
			(net "GND")
		)
	)
	(footprint ""
		(layer "F.Cu")
		(at 415.818828 -165.760654 180)
		(property "Reference" "PC2948"
			(at 0 0 180)
			(layer "F.SilkS")
			(hide yes)
			(effects
				(font
					(size 1.27 1.27)
				)
			)
		)
		(property "Value" ""
			(at 0 0 180)
			(layer "F.Fab")
			(effects
				(font
					(size 1.27 1.27)
				)
			)
		)
		(duplicate_pad_numbers_are_jumpers no)
		(fp_line
			(start 0.7874 0.4064)
			(end -0.7874 0.4064)
			(stroke
				(width 0.1524)
				(type default)
			)
			(layer "F.SilkS")
		)
		(fp_line
			(start 0.7874 -0.4064)
			(end 0.7874 0.4064)
			(stroke
				(width 0.1524)
				(type default)
			)
			(layer "F.SilkS")
		)
		(fp_line
			(start -0.7874 0.4064)
			(end -0.7874 -0.4064)
			(stroke
				(width 0.1524)
				(type default)
			)
			(layer "F.SilkS")
		)
		(fp_line
			(start -0.7874 -0.4064)
			(end 0.7874 -0.4064)
			(stroke
				(width 0.1524)
				(type default)
			)
			(layer "F.SilkS")
		)
		(fp_line
			(start 0.67945 0.3048)
			(end 0.120396 0.3048)
			(stroke
				(width 0.1)
				(type default)
			)
			(layer "F.Fab")
		)
		(fp_line
			(start 0.67945 -0.3048)
			(end 0.67945 0.3048)
			(stroke
				(width 0.1)
				(type default)
			)
			(layer "F.Fab")
		)
		(fp_line
			(start 0.12065 -0.2794)
			(end 0.12065 -0.3048)
			(stroke
				(width 0.1)
				(type default)
			)
			(layer "F.Fab")
		)
		(fp_line
			(start 0.12065 -0.3048)
			(end 0.67945 -0.3048)
			(stroke
				(width 0.1)
				(type default)
			)
			(layer "F.Fab")
		)
		(fp_line
			(start 0.120396 0.3048)
			(end 0.120396 0.2794)
			(stroke
				(width 0.1)
				(type default)
			)
			(layer "F.Fab")
		)
		(fp_line
			(start 0.120396 0.2794)
			(end -0.12065 0.2794)
			(stroke
				(width 0.1)
				(type default)
			)
			(layer "F.Fab")
		)
		(fp_line
			(start -0.12065 0.3048)
			(end -0.67945 0.3048)
			(stroke
				(width 0.1)
				(type default)
			)
			(layer "F.Fab")
		)
		(fp_line
			(start -0.12065 0.2794)
			(end -0.12065 0.3048)
			(stroke
				(width 0.1)
				(type default)
			)
			(layer "F.Fab")
		)
		(fp_line
			(start -0.12065 -0.2794)
			(end 0.12065 -0.2794)
			(stroke
				(width 0.1)
				(type default)
			)
			(layer "F.Fab")
		)
		(fp_line
			(start -0.12065 -0.305054)
			(end -0.12065 -0.2794)
			(stroke
				(width 0.1)
				(type default)
			)
			(layer "F.Fab")
		)
		(fp_line
			(start -0.67945 0.3048)
			(end -0.67945 -0.305054)
			(stroke
				(width 0.1)
				(type default)
			)
			(layer "F.Fab")
		)
		(fp_line
			(start -0.67945 -0.305054)
			(end -0.12065 -0.305054)
			(stroke
				(width 0.1)
				(type default)
			)
			(layer "F.Fab")
		)
		(pad "1" smd circle
			(at -0.40005 0 180)
			(size 0 0)
			(layers "F.Cu" "F.Mask" "F.Paste")
			(net "PVCCFA_EHV_CPU0_PVCC")
		)
		(pad "2" smd circle
			(at 0.40005 0 180)
			(size 0 0)
			(layers "F.Cu" "F.Mask" "F.Paste")
			(net "GND")
		)
	)
)
